(kicad_pcb
	(version 20260206)
	(generator "pcbnew")
	(generator_version "10.0")
	(general
		(thickness 1.6)
		(legacy_teardrops no)
	)
	(paper "A4")
	(title_block
		(title "netronome-mezz — pcbd0082-001_rev01_jul9_a.brd")
		(comment 1 "Open CloudServer (Microsoft) / footprints 388-398 of 714")
	)
	(layers
		(0 "F.Cu" signal "TOP")
		(4 "In1.Cu" signal "02_GND")
		(6 "In2.Cu" signal "03_SIG")
		(8 "In3.Cu" signal "04_SIG")
		(10 "In4.Cu" signal "05_GND")
		(12 "In5.Cu" signal "06_PWR1")
		(14 "In6.Cu" signal "07_SIG")
		(16 "In7.Cu" signal "08_SIG")
		(18 "In8.Cu" signal "09_GND")
		(2 "B.Cu" signal "BOTTOM")
		(9 "F.Adhes" user "F.Adhesive")
		(11 "B.Adhes" user "B.Adhesive")
		(13 "F.Paste" user "Package Geometry/Pastemask Top")
		(15 "B.Paste" user "Package Geometry/Pastemask Bottom")
		(5 "F.SilkS" user "Ref Des/Silkscreen Top")
		(7 "B.SilkS" user "Ref Des/Silkscreen Bottom")
		(1 "F.Mask" user "Board Geometry/Soldermask Top")
		(3 "B.Mask" user "Board Geometry/Soldermask Bottom")
		(17 "Dwgs.User" user "User.Drawings")
		(19 "Cmts.User" user "User.Comments")
		(21 "Eco1.User" user "User.Eco1")
		(23 "Eco2.User" user "User.Eco2")
		(25 "Edge.Cuts" user "Board Geometry/Outline")
		(27 "Margin" user)
		(31 "F.CrtYd" user "Package Geometry/Place Bound Top")
		(29 "B.CrtYd" user "Package Geometry/Place Bound Bottom")
		(35 "F.Fab" user "Ref Des/Assembly Top")
		(33 "B.Fab" user "Ref Des/Assembly Bottom")
		(45 "User.4" user "COMPVAL_TYPE_BOTTOM")
	)
	(footprint ""
		(layer "B.Cu")
		(at 23.495 7.874)
		(property "Reference" "R26"
			(at 0 0 0)
			(layer "B.SilkS")
			(hide yes)
			(effects
				(font
					(size 1.27 1.27)
				)
				(justify mirror)
			)
		)
		(property "Value" "4.75K"
			(at 0.148158 1.3462 270)
			(unlocked yes)
			(layer "B.Fab")
			(hide yes)
			(effects
				(font
					(size 1.27 0.9652)
					(thickness 0.000001)
				)
				(justify left mirror)
			)
		)
		(property "Device Type" "REST4024"
			(at 0.148158 1.3462 270)
			(unlocked yes)
			(layer "B.Fab")
			(hide yes)
			(effects
				(font
					(size 1.27 0.9652)
					(thickness 0.000001)
				)
				(justify left mirror)
			)
		)
		(duplicate_pad_numbers_are_jumpers no)
		(fp_poly
			(pts
				(xy -0.635 1.0668) (xy -0.635 -1.0668) (xy 0.635 -1.0668) (xy 0.635 1.0668)
			)
			(stroke
				(width 0)
				(type default)
			)
			(fill no)
			(layer "B.CrtYd")
		)
		(fp_line
			(start -0.254 -0.508)
			(end -0.254 0.508)
			(stroke
				(width 0.0254)
				(type default)
			)
			(layer "B.Fab")
		)
		(fp_line
			(start -0.254 0.508)
			(end 0.254 0.508)
			(stroke
				(width 0.0254)
				(type default)
			)
			(layer "B.Fab")
		)
		(fp_line
			(start 0.254 -0.508)
			(end -0.254 -0.508)
			(stroke
				(width 0.0254)
				(type default)
			)
			(layer "B.Fab")
		)
		(fp_line
			(start 0.254 0.508)
			(end 0.254 -0.508)
			(stroke
				(width 0.0254)
				(type default)
			)
			(layer "B.Fab")
		)
		(pad "1" smd rect
			(at 0 -0.4191 180)
			(size 0.508 0.5334)
			(layers "B.Cu" "B.Mask" "B.Paste")
			(net "VDD_3.3V")
		)
		(pad "2" smd rect
			(at 0 0.4191 180)
			(size 0.508 0.5334)
			(layers "B.Cu" "B.Mask" "B.Paste")
			(net "NFP_CFG_SPI_FLASH_SCK")
		)
		(zone
			(layer "B.Cu")
			(hatch none 0.5)
			(connect_pads
				(clearance 0)
			)
			(min_thickness 0.25)
			(keepout
				(tracks not_allowed)
				(vias allowed)
				(pads allowed)
				(copperpour not_allowed)
				(footprints allowed)
			)
			(placement
				(enabled no)
				(sheetname "")
			)
			(fill
				(thermal_gap 0.5)
				(thermal_bridge_width 0.5)
				(island_removal_mode 0)
			)
			(polygon
				(pts
					(xy 23.4696 7.8486) (xy 23.4696 7.8994) (xy 23.5204 7.8994) (xy 23.5204 7.8486)
				)
			)
		)
	)
	(footprint ""
		(layer "B.Cu")
		(at 84.250987 25.813004)
		(property "Reference" "V3_A-A13"
			(at 0 0 0)
			(layer "B.SilkS")
			(hide yes)
			(effects
				(font
					(size 1.27 1.27)
				)
				(justify mirror)
			)
		)
		(property "Value" ""
			(at 0 0 0)
			(layer "B.Fab")
			(effects
				(font
					(size 1.27 1.27)
				)
				(justify mirror)
			)
		)
		(duplicate_pad_numbers_are_jumpers no)
		(pad "1" thru_hole circle
			(at 0 0 180)
			(size 0.4572 0.4572)
			(drill 0.20574)
			(layers "*.Cu" "*.Mask")
			(remove_unused_layers no)
			(net "DDR0_32A_A13")
			(clearance 0.1143)
			(thermal_gap 0.1143)
		)
	)
	(footprint ""
		(layer "B.Cu")
		(at 56.8452 35.56 -90)
		(property "Reference" "C11"
			(at -1.87833 -1.4478 0)
			(unlocked yes)
			(layer "B.SilkS")
			(effects
				(font
					(size 0.7874 0.5842)
					(thickness 0.127)
				)
				(justify left mirror)
			)
		)
		(property "Value" "22UF"
			(at 0.148158 1.7526 180)
			(unlocked yes)
			(layer "B.Fab")
			(hide yes)
			(effects
				(font
					(size 1.27 0.9652)
					(thickness 0.000001)
				)
				(justify left mirror)
			)
		)
		(property "Device Type" "CAPC0063"
			(at 0.148158 1.7526 180)
			(unlocked yes)
			(layer "B.Fab")
			(hide yes)
			(effects
				(font
					(size 1.27 0.9652)
					(thickness 0.000001)
				)
				(justify left mirror)
			)
		)
		(duplicate_pad_numbers_are_jumpers no)
		(fp_circle
			(center 0 0)
			(end 0 -0.127)
			(stroke
				(width 0.2032)
				(type default)
			)
			(fill no)
			(layer "B.SilkS")
		)
		(fp_poly
			(pts
				(xy -0.7874 -1.6637) (xy 0.7874 -1.6637) (xy 0.7874 1.6637) (xy -0.7874 1.6637)
			)
			(stroke
				(width 0)
				(type default)
			)
			(fill no)
			(layer "B.CrtYd")
		)
		(fp_line
			(start -0.4064 0.8128)
			(end 0.4064 0.8128)
			(stroke
				(width 0.0254)
				(type default)
			)
			(layer "B.Fab")
		)
		(fp_line
			(start 0.4064 0.8128)
			(end 0.4064 -0.7874)
			(stroke
				(width 0.0254)
				(type default)
			)
			(layer "B.Fab")
		)
		(fp_line
			(start -0.4064 -0.7874)
			(end -0.4064 0.8128)
			(stroke
				(width 0.0254)
				(type default)
			)
			(layer "B.Fab")
		)
		(fp_line
			(start 0.4064 -0.7874)
			(end -0.4064 -0.7874)
			(stroke
				(width 0.0254)
				(type default)
			)
			(layer "B.Fab")
		)
		(pad "1" smd rect
			(at 0 -0.8001 90)
			(size 0.8636 0.9652)
			(layers "B.Cu" "B.Mask" "B.Paste")
			(net "VDD_CORE")
		)
		(pad "2" smd rect
			(at 0 0.8001 90)
			(size 0.8636 0.9652)
			(layers "B.Cu" "B.Mask" "B.Paste")
			(net "GND")
		)
		(zone
			(layer "B.Cu")
			(hatch none 0.5)
			(connect_pads
				(clearance 0)
			)
			(min_thickness 0.25)
			(keepout
				(tracks not_allowed)
				(vias allowed)
				(pads allowed)
				(copperpour not_allowed)
				(footprints allowed)
			)
			(placement
				(enabled no)
				(sheetname "")
			)
			(fill
				(thermal_gap 0.5)
				(thermal_bridge_width 0.5)
				(island_removal_mode 0)
			)
			(polygon
				(pts
					(xy 57.0992 35.6235) (xy 57.0992 35.4965) (xy 56.5912 35.4965) (xy 56.5912 35.6235)
				)
			)
		)
	)
	(footprint ""
		(layer "B.Cu")
		(at 37.084 48.641)
		(property "Reference" "TP2"
			(at 2.13233 3.429 270)
			(unlocked yes)
			(layer "B.SilkS")
			(effects
				(font
					(size 0.7874 0.5842)
					(thickness 0.127)
				)
				(justify left mirror)
			)
		)
		(property "Value" "*"
			(at 0.4826 -0.14732 0)
			(unlocked yes)
			(layer "B.Fab")
			(hide yes)
			(effects
				(font
					(size 1.27 0.9652)
					(thickness 0.000001)
				)
				(justify left mirror)
			)
		)
		(property "Device Type" "TP_SMALL"
			(at 0.4826 -0.14732 0)
			(unlocked yes)
			(layer "B.Fab")
			(hide yes)
			(effects
				(font
					(size 1.27 0.9652)
					(thickness 0.000001)
				)
				(justify left mirror)
			)
		)
		(duplicate_pad_numbers_are_jumpers no)
		(fp_line
			(start -0.8636 -0.8636)
			(end 0.8636 -0.8636)
			(stroke
				(width 0.1524)
				(type default)
			)
			(layer "B.SilkS")
		)
		(fp_line
			(start -0.8636 0.8636)
			(end -0.8636 -0.8636)
			(stroke
				(width 0.1524)
				(type default)
			)
			(layer "B.SilkS")
		)
		(fp_line
			(start 0.8636 -0.8636)
			(end 0.8636 0.8636)
			(stroke
				(width 0.1524)
				(type default)
			)
			(layer "B.SilkS")
		)
		(fp_line
			(start 0.8636 0.8636)
			(end -0.8636 0.8636)
			(stroke
				(width 0.1524)
				(type default)
			)
			(layer "B.SilkS")
		)
		(fp_poly
			(pts
				(xy 0.635 -0.635) (xy 0.635 0.635) (xy -0.635 0.635) (xy -0.635 -0.635)
			)
			(stroke
				(width 0)
				(type default)
			)
			(fill no)
			(layer "B.CrtYd")
		)
		(pad "1" smd rect
			(at 0 0 180)
			(size 1.27 1.27)
			(layers "B.Cu" "B.Mask" "B.Paste")
			(net "CNTRL_SPI_MOSI")
		)
	)
	(footprint ""
		(layer "B.Cu")
		(at 83.450989 7.498994)
		(property "Reference" "V1_A-A06"
			(at 0 0 0)
			(layer "B.SilkS")
			(hide yes)
			(effects
				(font
					(size 1.27 1.27)
				)
				(justify mirror)
			)
		)
		(property "Value" ""
			(at 0 0 0)
			(layer "B.Fab")
			(effects
				(font
					(size 1.27 1.27)
				)
				(justify mirror)
			)
		)
		(duplicate_pad_numbers_are_jumpers no)
		(pad "1" thru_hole circle
			(at 0 0 180)
			(size 0.4572 0.4572)
			(drill 0.20574)
			(layers "*.Cu" "*.Mask")
			(remove_unused_layers no)
			(net "DDR0_32A_A6")
			(clearance 0.1143)
			(thermal_gap 0.1143)
		)
	)
	(footprint ""
		(layer "B.Cu")
		(at 5.334 12.827 180)
		(property "Reference" "C285"
			(at -1.62433 -1.778 270)
			(unlocked yes)
			(layer "B.SilkS")
			(effects
				(font
					(size 0.7874 0.5842)
					(thickness 0.127)
				)
				(justify left mirror)
			)
		)
		(property "Value" "0.1UF"
			(at 0.091846 0.2921 90)
			(unlocked yes)
			(layer "B.Fab")
			(hide yes)
			(effects
				(font
					(size 0.7874 0.5842)
					(thickness 0.2032)
				)
				(justify left mirror)
			)
		)
		(property "Device Type" "CAPC0073"
			(at 0.091846 0.2921 90)
			(unlocked yes)
			(layer "B.Fab")
			(hide yes)
			(effects
				(font
					(size 0.7874 0.5842)
					(thickness 0.2032)
				)
				(justify left mirror)
			)
		)
		(duplicate_pad_numbers_are_jumpers no)
		(fp_poly
			(pts
				(xy -0.635 1.0668) (xy -0.635 -1.0668) (xy 0.635 -1.0668) (xy 0.635 1.0668)
			)
			(stroke
				(width 0)
				(type default)
			)
			(fill no)
			(layer "B.CrtYd")
		)
		(fp_line
			(start 0.254 0.508)
			(end 0.254 -0.508)
			(stroke
				(width 0.0254)
				(type default)
			)
			(layer "B.Fab")
		)
		(fp_line
			(start 0.254 -0.508)
			(end -0.254 -0.508)
			(stroke
				(width 0.0254)
				(type default)
			)
			(layer "B.Fab")
		)
		(fp_line
			(start -0.254 0.508)
			(end 0.254 0.508)
			(stroke
				(width 0.0254)
				(type default)
			)
			(layer "B.Fab")
		)
		(fp_line
			(start -0.254 -0.508)
			(end -0.254 0.508)
			(stroke
				(width 0.0254)
				(type default)
			)
			(layer "B.Fab")
		)
		(pad "1" smd rect
			(at 0 -0.4191)
			(size 0.508 0.5334)
			(layers "B.Cu" "B.Mask" "B.Paste")
			(net "EXT_3.3V")
		)
		(pad "2" smd rect
			(at 0 0.4191)
			(size 0.508 0.5334)
			(layers "B.Cu" "B.Mask" "B.Paste")
			(net "GND")
		)
		(zone
			(layer "B.Cu")
			(hatch none 0.5)
			(connect_pads
				(clearance 0)
			)
			(min_thickness 0.25)
			(keepout
				(tracks not_allowed)
				(vias allowed)
				(pads allowed)
				(copperpour not_allowed)
				(footprints allowed)
			)
			(placement
				(enabled no)
				(sheetname "")
			)
			(fill
				(thermal_gap 0.5)
				(thermal_bridge_width 0.5)
				(island_removal_mode 0)
			)
			(polygon
				(pts
					(xy 5.3594 12.8524) (xy 5.3594 12.8016) (xy 5.3086 12.8016) (xy 5.3086 12.8524)
				)
			)
		)
	)
	(footprint ""
		(layer "B.Cu")
		(at 43.737022 25.041987 90)
		(property "Reference" "C25"
			(at 0.123317 2.490978 0)
			(unlocked yes)
			(layer "B.SilkS")
			(effects
				(font
					(size 0.7874 0.5842)
					(thickness 0.127)
				)
				(justify mirror)
			)
		)
		(property "Value" ""
			(at 0 0 90)
			(layer "B.Fab")
			(effects
				(font
					(size 1.27 1.27)
				)
				(justify mirror)
			)
		)
		(duplicate_pad_numbers_are_jumpers no)
		(fp_circle
			(center 0 0)
			(end 0 0.104648)
			(stroke
				(width 0.1016)
				(type default)
			)
			(fill no)
			(layer "B.SilkS")
		)
		(fp_poly
			(pts
				(xy 0.381 -0.889) (xy 0.381 0.889) (xy -0.381 0.889) (xy -0.381 -0.889)
			)
			(stroke
				(width 0)
				(type default)
			)
			(fill no)
			(layer "B.CrtYd")
		)
		(fp_line
			(start 0.508 -1.016)
			(end 0.254 -1.016)
			(stroke
				(width 0.0254)
				(type default)
			)
			(layer "B.Fab")
		)
		(fp_line
			(start 0.254 -1.016)
			(end -0.508 -1.016)
			(stroke
				(width 0.0254)
				(type default)
			)
			(layer "B.Fab")
		)
		(fp_line
			(start -0.508 -1.016)
			(end -0.508 1.016)
			(stroke
				(width 0.0254)
				(type default)
			)
			(layer "B.Fab")
		)
		(fp_line
			(start 0.508 1.016)
			(end 0.508 -1.016)
			(stroke
				(width 0.0254)
				(type default)
			)
			(layer "B.Fab")
		)
		(fp_line
			(start -0.508 1.016)
			(end 0.508 1.016)
			(stroke
				(width 0.0254)
				(type default)
			)
			(layer "B.Fab")
		)
		(pad "1" smd custom
			(at 0 -0.500126 270)
			(size 0.127 0.127)
			(layers "B.Cu" "B.Mask" "B.Paste")
			(net "VDDA_PLL")
			(options
				(clearance outline)
				(anchor circle)
			)
			(primitives
				(gr_poly
					(pts
						(xy -0.1778 0.254) (xy 0.1778 0.254) (xy 0.254 0.1778) (xy 0.254 -0.1778) (xy 0.1778 -0.254) (xy -0.1778 -0.254)
						(xy -0.254 -0.1778) (xy -0.254 0.1778)
					)
					(width 0)
					(fill yes)
				)
			)
		)
		(pad "2" smd custom
			(at 0 0.500126 270)
			(size 0.127 0.127)
			(layers "B.Cu" "B.Mask" "B.Paste")
			(net "GND")
			(options
				(clearance outline)
				(anchor circle)
			)
			(primitives
				(gr_poly
					(pts
						(xy -0.1778 0.254) (xy 0.1778 0.254) (xy 0.254 0.1778) (xy 0.254 -0.1778) (xy 0.1778 -0.254) (xy -0.1778 -0.254)
						(xy -0.254 -0.1778) (xy -0.254 0.1778)
					)
					(width 0)
					(fill yes)
				)
			)
		)
	)
	(footprint ""
		(layer "B.Cu")
		(at 58.236993 29.541978)
		(property "Reference" "C199"
			(at 0 0 0)
			(layer "B.SilkS")
			(hide yes)
			(effects
				(font
					(size 1.27 1.27)
				)
				(justify mirror)
			)
		)
		(property "Value" ""
			(at 0 0 0)
			(layer "B.Fab")
			(effects
				(font
					(size 1.27 1.27)
				)
				(justify mirror)
			)
		)
		(duplicate_pad_numbers_are_jumpers no)
		(fp_circle
			(center 0 0)
			(end 0.104648 0)
			(stroke
				(width 0.1016)
				(type default)
			)
			(fill no)
			(layer "B.SilkS")
		)
		(fp_poly
			(pts
				(xy 0.381 -0.889) (xy 0.381 0.889) (xy -0.381 0.889) (xy -0.381 -0.889)
			)
			(stroke
				(width 0)
				(type default)
			)
			(fill no)
			(layer "B.CrtYd")
		)
		(fp_line
			(start -0.508 -1.016)
			(end -0.508 1.016)
			(stroke
				(width 0.0254)
				(type default)
			)
			(layer "B.Fab")
		)
		(fp_line
			(start -0.508 1.016)
			(end 0.508 1.016)
			(stroke
				(width 0.0254)
				(type default)
			)
			(layer "B.Fab")
		)
		(fp_line
			(start 0.254 -1.016)
			(end -0.508 -1.016)
			(stroke
				(width 0.0254)
				(type default)
			)
			(layer "B.Fab")
		)
		(fp_line
			(start 0.508 -1.016)
			(end 0.254 -1.016)
			(stroke
				(width 0.0254)
				(type default)
			)
			(layer "B.Fab")
		)
		(fp_line
			(start 0.508 1.016)
			(end 0.508 -1.016)
			(stroke
				(width 0.0254)
				(type default)
			)
			(layer "B.Fab")
		)
		(pad "1" smd custom
			(at 0 -0.500126 180)
			(size 0.127 0.127)
			(layers "B.Cu" "B.Mask" "B.Paste")
			(net "VDD_CORE")
			(options
				(clearance outline)
				(anchor circle)
			)
			(primitives
				(gr_poly
					(pts
						(xy -0.1778 0.254) (xy 0.1778 0.254) (xy 0.254 0.1778) (xy 0.254 -0.1778) (xy 0.1778 -0.254) (xy -0.1778 -0.254)
						(xy -0.254 -0.1778) (xy -0.254 0.1778)
					)
					(width 0)
					(fill yes)
				)
			)
		)
		(pad "2" smd custom
			(at 0 0.500126 180)
			(size 0.127 0.127)
			(layers "B.Cu" "B.Mask" "B.Paste")
			(net "GND")
			(options
				(clearance outline)
				(anchor circle)
			)
			(primitives
				(gr_poly
					(pts
						(xy -0.1778 0.254) (xy 0.1778 0.254) (xy 0.254 0.1778) (xy 0.254 -0.1778) (xy 0.1778 -0.254) (xy -0.1778 -0.254)
						(xy -0.254 -0.1778) (xy -0.254 0.1778)
					)
					(width 0)
					(fill yes)
				)
			)
		)
	)
	(footprint ""
		(layer "B.Cu")
		(at 24.765 7.874)
		(property "Reference" "R27"
			(at 0.98933 -0.635 270)
			(unlocked yes)
			(layer "B.SilkS")
			(effects
				(font
					(size 0.7874 0.5842)
					(thickness 0.127)
				)
				(justify left mirror)
			)
		)
		(property "Value" "4.75K"
			(at 0.148158 1.3462 270)
			(unlocked yes)
			(layer "B.Fab")
			(hide yes)
			(effects
				(font
					(size 1.27 0.9652)
					(thickness 0.000001)
				)
				(justify left mirror)
			)
		)
		(property "Device Type" "REST4024"
			(at 0.148158 1.3462 270)
			(unlocked yes)
			(layer "B.Fab")
			(hide yes)
			(effects
				(font
					(size 1.27 0.9652)
					(thickness 0.000001)
				)
				(justify left mirror)
			)
		)
		(duplicate_pad_numbers_are_jumpers no)
		(fp_poly
			(pts
				(xy -0.635 1.0668) (xy -0.635 -1.0668) (xy 0.635 -1.0668) (xy 0.635 1.0668)
			)
			(stroke
				(width 0)
				(type default)
			)
			(fill no)
			(layer "B.CrtYd")
		)
		(fp_line
			(start -0.254 -0.508)
			(end -0.254 0.508)
			(stroke
				(width 0.0254)
				(type default)
			)
			(layer "B.Fab")
		)
		(fp_line
			(start -0.254 0.508)
			(end 0.254 0.508)
			(stroke
				(width 0.0254)
				(type default)
			)
			(layer "B.Fab")
		)
		(fp_line
			(start 0.254 -0.508)
			(end -0.254 -0.508)
			(stroke
				(width 0.0254)
				(type default)
			)
			(layer "B.Fab")
		)
		(fp_line
			(start 0.254 0.508)
			(end 0.254 -0.508)
			(stroke
				(width 0.0254)
				(type default)
			)
			(layer "B.Fab")
		)
		(pad "1" smd rect
			(at 0 -0.4191 180)
			(size 0.508 0.5334)
			(layers "B.Cu" "B.Mask" "B.Paste")
			(net "VDD_3.3V")
		)
		(pad "2" smd rect
			(at 0 0.4191 180)
			(size 0.508 0.5334)
			(layers "B.Cu" "B.Mask" "B.Paste")
			(net "NFP_CFG_SPI_FLASH_MOSI")
		)
		(zone
			(layer "B.Cu")
			(hatch none 0.5)
			(connect_pads
				(clearance 0)
			)
			(min_thickness 0.25)
			(keepout
				(tracks not_allowed)
				(vias allowed)
				(pads allowed)
				(copperpour not_allowed)
				(footprints allowed)
			)
			(placement
				(enabled no)
				(sheetname "")
			)
			(fill
				(thermal_gap 0.5)
				(thermal_bridge_width 0.5)
				(island_removal_mode 0)
			)
			(polygon
				(pts
					(xy 24.7396 7.8486) (xy 24.7396 7.8994) (xy 24.7904 7.8994) (xy 24.7904 7.8486)
				)
			)
		)
	)
	(footprint ""
		(layer "B.Cu")
		(at 81.850992 29.812996)
		(property "Reference" "V3_A-A12"
			(at 0 0 0)
			(layer "B.SilkS")
			(hide yes)
			(effects
				(font
					(size 1.27 1.27)
				)
				(justify mirror)
			)
		)
		(property "Value" ""
			(at 0 0 0)
			(layer "B.Fab")
			(effects
				(font
					(size 1.27 1.27)
				)
				(justify mirror)
			)
		)
		(duplicate_pad_numbers_are_jumpers no)
		(pad "1" thru_hole circle
			(at 0 0 180)
			(size 0.4572 0.4572)
			(drill 0.20574)
			(layers "*.Cu" "*.Mask")
			(remove_unused_layers no)
			(net "DDR0_32A_A12")
			(clearance 0.1143)
			(thermal_gap 0.1143)
		)
	)
	(footprint ""
		(layer "B.Cu")
		(at 83.450989 14.256004)
		(property "Reference" "V2_A-A09"
			(at 0 0 0)
			(layer "B.SilkS")
			(hide yes)
			(effects
				(font
					(size 1.27 1.27)
				)
				(justify mirror)
			)
		)
		(property "Value" ""
			(at 0 0 0)
			(layer "B.Fab")
			(effects
				(font
					(size 1.27 1.27)
				)
				(justify mirror)
			)
		)
		(duplicate_pad_numbers_are_jumpers no)
		(pad "1" thru_hole circle
			(at 0 0 180)
			(size 0.4572 0.4572)
			(drill 0.20574)
			(layers "*.Cu" "*.Mask")
			(remove_unused_layers no)
			(net "DDR0_32A_A9")
			(clearance 0.1143)
			(thermal_gap 0.1143)
		)
	)
)
